(kicad_pcb
	(version 20260206)
	(generator "pcbnew")
	(generator_version "10.0")
	(general
		(thickness 1.6)
		(legacy_teardrops no)
	)
	(paper "A4")
	(title_block
		(title "Bryce Canyon_IOM_IOC_16318-2_OCP.brd")
		(comment 1 "Bryce Canyon / footprints 1298-1304 of 1605")
	)
	(layers
		(0 "F.Cu" signal "TOP")
		(4 "In1.Cu" signal "L2GND")
		(6 "In2.Cu" signal "L3")
		(8 "In3.Cu" signal "L4VCC")
		(10 "In4.Cu" signal "L5VCC")
		(12 "In5.Cu" signal "L6")
		(14 "In6.Cu" signal "L7GND")
		(2 "B.Cu" signal "BOTTOM")
		(9 "F.Adhes" user "F.Adhesive")
		(11 "B.Adhes" user "B.Adhesive")
		(13 "F.Paste" user "Package Geometry/Pastemask Top")
		(15 "B.Paste" user "Package Geometry/Pastemask Bottom")
		(5 "F.SilkS" user "Ref Des/Silkscreen Top")
		(7 "B.SilkS" user "Ref Des/Silkscreen Bottom")
		(1 "F.Mask" user "Board Geometry/Soldermask Top")
		(3 "B.Mask" user "Board Geometry/Soldermask Bottom")
		(17 "Dwgs.User" user "User.Drawings")
		(19 "Cmts.User" user "User.Comments")
		(21 "Eco1.User" user "User.Eco1")
		(23 "Eco2.User" user "User.Eco2")
		(25 "Edge.Cuts" user "Board Geometry/Outline")
		(27 "Margin" user)
		(31 "F.CrtYd" user "Package Geometry/Place Bound Top")
		(29 "B.CrtYd" user "Package Geometry/Place Bound Bottom")
		(35 "F.Fab" user "Ref Des/Assembly Top")
		(33 "B.Fab" user "Ref Des/Assembly Bottom")
	)
	(footprint ""
		(layer "B.Cu")
		(at 188.43244 -73.10374 90)
		(property "Reference" "C452"
			(at 0 0 90)
			(layer "B.SilkS")
			(hide yes)
			(effects
				(font
					(size 1.27 1.27)
				)
				(justify mirror)
			)
		)
		(property "Value" "SCD1U16V2KX-3GP"
			(at -1.1811 -2.7051 90)
			(unlocked yes)
			(layer "B.Fab")
			(hide yes)
			(effects
				(font
					(size 1.016 1.016)
					(thickness 0.1524)
				)
				(justify mirror)
			)
		)
		(property "Device Type" "C402H22"
			(at -1.1811 -4.2291 90)
			(unlocked yes)
			(layer "B.Fab")
			(hide yes)
			(effects
				(font
					(size 1.016 1.016)
					(thickness 0.1524)
				)
				(justify mirror)
			)
		)
		(duplicate_pad_numbers_are_jumpers no)
		(fp_rect
			(start 0.4318 0.9525)
			(end -0.4318 -0.9525)
			(stroke
				(width 0)
				(type default)
			)
			(fill no)
			(layer "B.CrtYd")
		)
		(fp_rect
			(start 0.4318 0.9525)
			(end -0.4318 -0.9525)
			(stroke
				(width 0)
				(type default)
			)
			(fill no)
			(layer "B.Fab")
		)
		(pad "1" smd custom
			(at 0 -0.4445 270)
			(size 0.1524 0.1524)
			(layers "B.Cu" "B.Mask" "B.Paste")
			(net "P1V8")
			(options
				(clearance outline)
				(anchor circle)
			)
			(primitives
				(gr_poly
					(pts
						(arc
							(start 0.3048 0.2032)
							(mid 0.275042 0.275042)
							(end 0.2032 0.3048)
						)
						(arc
							(start -0.2032 0.3048)
							(mid -0.275042 0.275042)
							(end -0.3048 0.2032)
						)
						(arc
							(start -0.3048 -0.2032)
							(mid -0.275042 -0.275042)
							(end -0.2032 -0.3048)
						)
						(arc
							(start 0.2032 -0.3048)
							(mid 0.275042 -0.275042)
							(end 0.3048 -0.2032)
						)
					)
					(width 0)
					(fill yes)
				)
			)
		)
		(pad "2" smd custom
			(at 0 0.4445 270)
			(size 0.1524 0.1524)
			(layers "B.Cu" "B.Mask" "B.Paste")
			(net "GND")
			(options
				(clearance outline)
				(anchor circle)
			)
			(primitives
				(gr_poly
					(pts
						(arc
							(start 0.3048 0.2032)
							(mid 0.275042 0.275042)
							(end 0.2032 0.3048)
						)
						(arc
							(start -0.2032 0.3048)
							(mid -0.275042 0.275042)
							(end -0.3048 0.2032)
						)
						(arc
							(start -0.3048 -0.2032)
							(mid -0.275042 -0.275042)
							(end -0.2032 -0.3048)
						)
						(arc
							(start 0.2032 -0.3048)
							(mid 0.275042 -0.275042)
							(end 0.3048 -0.2032)
						)
					)
					(width 0)
					(fill yes)
				)
			)
		)
	)
	(footprint ""
		(layer "B.Cu")
		(at 184.61482 -73.13422 90)
		(property "Reference" "R650"
			(at 0 0 90)
			(layer "B.SilkS")
			(hide yes)
			(effects
				(font
					(size 1.27 1.27)
				)
				(justify mirror)
			)
		)
		(property "Value" "10KR2F-2-GP"
			(at -0.064008 -3.993896 90)
			(unlocked yes)
			(layer "B.Fab")
			(hide yes)
			(effects
				(font
					(size 1.016 1.016)
					(thickness 0.1524)
				)
				(justify mirror)
			)
		)
		(property "Device Type" "R402H16"
			(at -0.064008 -5.517896 90)
			(unlocked yes)
			(layer "B.Fab")
			(hide yes)
			(effects
				(font
					(size 1.016 1.016)
					(thickness 0.1524)
				)
				(justify mirror)
			)
		)
		(duplicate_pad_numbers_are_jumpers no)
		(fp_line
			(start 0.508 -0.9398)
			(end 0.508 0.9398)
			(stroke
				(width 0.1524)
				(type default)
			)
			(layer "B.SilkS")
		)
		(fp_line
			(start -0.508 -0.9398)
			(end 0.508 -0.9398)
			(stroke
				(width 0.1524)
				(type default)
			)
			(layer "B.SilkS")
		)
		(fp_rect
			(start 0.508 0.9398)
			(end -0.508 -0.9398)
			(stroke
				(width 0)
				(type default)
			)
			(fill no)
			(layer "B.CrtYd")
		)
		(fp_rect
			(start 0.508 0.9398)
			(end -0.508 -0.9398)
			(stroke
				(width 0)
				(type default)
			)
			(fill no)
			(layer "B.Fab")
		)
		(pad "1" smd custom
			(at 0 -0.4445 270)
			(size 0.1397 0.1397)
			(layers "B.Cu" "B.Mask" "B.Paste")
			(net "P1V8")
			(options
				(clearance outline)
				(anchor circle)
			)
			(primitives
				(gr_poly
					(pts
						(arc
							(start -0.1778 0.2794)
							(mid -0.249642 0.249642)
							(end -0.2794 0.1778)
						)
						(arc
							(start -0.2794 -0.1778)
							(mid -0.249642 -0.249642)
							(end -0.1778 -0.2794)
						)
						(arc
							(start 0.1778 -0.2794)
							(mid 0.249642 -0.249642)
							(end 0.2794 -0.1778)
						)
						(arc
							(start 0.2794 0.1778)
							(mid 0.249642 0.249642)
							(end 0.1778 0.2794)
						)
					)
					(width 0)
					(fill yes)
				)
			)
		)
		(pad "2" smd custom
			(at 0 0.4445 270)
			(size 0.1397 0.1397)
			(layers "B.Cu" "B.Mask" "B.Paste")
			(net "SYS_RST_N_1")
			(options
				(clearance outline)
				(anchor circle)
			)
			(primitives
				(gr_poly
					(pts
						(arc
							(start -0.1778 0.2794)
							(mid -0.249642 0.249642)
							(end -0.2794 0.1778)
						)
						(arc
							(start -0.2794 -0.1778)
							(mid -0.249642 -0.249642)
							(end -0.1778 -0.2794)
						)
						(arc
							(start 0.1778 -0.2794)
							(mid 0.249642 -0.249642)
							(end 0.2794 -0.1778)
						)
						(arc
							(start 0.2794 0.1778)
							(mid 0.249642 0.249642)
							(end 0.1778 0.2794)
						)
					)
					(width 0)
					(fill yes)
				)
			)
		)
	)
	(footprint ""
		(layer "B.Cu")
		(at 12.091924 -135.285988 90)
		(property "Reference" "R257"
			(at 0 0 90)
			(layer "B.SilkS")
			(hide yes)
			(effects
				(font
					(size 1.27 1.27)
				)
				(justify mirror)
			)
		)
		(property "Value" "120R2F-GP"
			(at -0.064008 -3.993896 90)
			(unlocked yes)
			(layer "B.Fab")
			(hide yes)
			(effects
				(font
					(size 1.016 1.016)
					(thickness 0.1524)
				)
				(justify mirror)
			)
		)
		(property "Device Type" "R402H16"
			(at -0.064008 -5.517896 90)
			(unlocked yes)
			(layer "B.Fab")
			(hide yes)
			(effects
				(font
					(size 1.016 1.016)
					(thickness 0.1524)
				)
				(justify mirror)
			)
		)
		(duplicate_pad_numbers_are_jumpers no)
		(fp_line
			(start 0.508 -0.9398)
			(end 0.508 0.9398)
			(stroke
				(width 0.1524)
				(type default)
			)
			(layer "B.SilkS")
		)
		(fp_line
			(start -0.508 -0.9398)
			(end 0.508 -0.9398)
			(stroke
				(width 0.1524)
				(type default)
			)
			(layer "B.SilkS")
		)
		(fp_rect
			(start 0.508 0.9398)
			(end -0.508 -0.9398)
			(stroke
				(width 0)
				(type default)
			)
			(fill no)
			(layer "B.CrtYd")
		)
		(fp_rect
			(start 0.508 0.9398)
			(end -0.508 -0.9398)
			(stroke
				(width 0)
				(type default)
			)
			(fill no)
			(layer "B.Fab")
		)
		(pad "1" smd custom
			(at 0 -0.4445 270)
			(size 0.1397 0.1397)
			(layers "B.Cu" "B.Mask" "B.Paste")
			(net "MEMA_11")
			(options
				(clearance outline)
				(anchor circle)
			)
			(primitives
				(gr_poly
					(pts
						(arc
							(start -0.1778 0.2794)
							(mid -0.249642 0.249642)
							(end -0.2794 0.1778)
						)
						(arc
							(start -0.2794 -0.1778)
							(mid -0.249642 -0.249642)
							(end -0.1778 -0.2794)
						)
						(arc
							(start 0.1778 -0.2794)
							(mid 0.249642 -0.249642)
							(end 0.2794 -0.1778)
						)
						(arc
							(start 0.2794 0.1778)
							(mid 0.249642 0.249642)
							(end 0.1778 0.2794)
						)
					)
					(width 0)
					(fill yes)
				)
			)
		)
		(pad "2" smd custom
			(at 0 0.4445 270)
			(size 0.1397 0.1397)
			(layers "B.Cu" "B.Mask" "B.Paste")
			(net "P1V2_STBY")
			(options
				(clearance outline)
				(anchor circle)
			)
			(primitives
				(gr_poly
					(pts
						(arc
							(start -0.1778 0.2794)
							(mid -0.249642 0.249642)
							(end -0.2794 0.1778)
						)
						(arc
							(start -0.2794 -0.1778)
							(mid -0.249642 -0.249642)
							(end -0.1778 -0.2794)
						)
						(arc
							(start 0.1778 -0.2794)
							(mid 0.249642 -0.249642)
							(end 0.2794 -0.1778)
						)
						(arc
							(start 0.2794 0.1778)
							(mid 0.249642 0.249642)
							(end 0.1778 0.2794)
						)
					)
					(width 0)
					(fill yes)
				)
			)
		)
	)
	(footprint ""
		(layer "B.Cu")
		(at 80.8228 -167.1574 -90)
		(property "Reference" "R452"
			(at 0 0 90)
			(layer "B.SilkS")
			(hide yes)
			(effects
				(font
					(size 1.27 1.27)
				)
				(justify mirror)
			)
		)
		(property "Value" "0R2J-2-GP"
			(at -0.064008 -3.993896 270)
			(unlocked yes)
			(layer "B.Fab")
			(hide yes)
			(effects
				(font
					(size 1.016 1.016)
					(thickness 0.1524)
				)
				(justify mirror)
			)
		)
		(property "Device Type" "R402H16"
			(at -0.064008 -5.517896 270)
			(unlocked yes)
			(layer "B.Fab")
			(hide yes)
			(effects
				(font
					(size 1.016 1.016)
					(thickness 0.1524)
				)
				(justify mirror)
			)
		)
		(duplicate_pad_numbers_are_jumpers no)
		(fp_line
			(start -0.508 -0.9398)
			(end 0.508 -0.9398)
			(stroke
				(width 0.1524)
				(type default)
			)
			(layer "B.SilkS")
		)
		(fp_line
			(start 0.508 -0.9398)
			(end 0.508 0.9398)
			(stroke
				(width 0.1524)
				(type default)
			)
			(layer "B.SilkS")
		)
		(fp_rect
			(start 0.508 0.9398)
			(end -0.508 -0.9398)
			(stroke
				(width 0)
				(type default)
			)
			(fill no)
			(layer "B.CrtYd")
		)
		(fp_rect
			(start 0.508 0.9398)
			(end -0.508 -0.9398)
			(stroke
				(width 0)
				(type default)
			)
			(fill no)
			(layer "B.Fab")
		)
		(pad "1" smd custom
			(at 0 -0.4445 90)
			(size 0.1397 0.1397)
			(layers "B.Cu" "B.Mask" "B.Paste")
			(net "UART_SDB_TX_R")
			(options
				(clearance outline)
				(anchor circle)
			)
			(primitives
				(gr_poly
					(pts
						(arc
							(start -0.1778 0.2794)
							(mid -0.249642 0.249642)
							(end -0.2794 0.1778)
						)
						(arc
							(start -0.2794 -0.1778)
							(mid -0.249642 -0.249642)
							(end -0.1778 -0.2794)
						)
						(arc
							(start 0.1778 -0.2794)
							(mid 0.249642 -0.249642)
							(end 0.2794 -0.1778)
						)
						(arc
							(start 0.2794 0.1778)
							(mid 0.249642 0.249642)
							(end 0.1778 0.2794)
						)
					)
					(width 0)
					(fill yes)
				)
			)
		)
		(pad "2" smd custom
			(at 0 0.4445 90)
			(size 0.1397 0.1397)
			(layers "B.Cu" "B.Mask" "B.Paste")
			(net "UART_SDB_TX")
			(options
				(clearance outline)
				(anchor circle)
			)
			(primitives
				(gr_poly
					(pts
						(arc
							(start -0.1778 0.2794)
							(mid -0.249642 0.249642)
							(end -0.2794 0.1778)
						)
						(arc
							(start -0.2794 -0.1778)
							(mid -0.249642 -0.249642)
							(end -0.1778 -0.2794)
						)
						(arc
							(start 0.1778 -0.2794)
							(mid 0.249642 -0.249642)
							(end 0.2794 -0.1778)
						)
						(arc
							(start 0.2794 0.1778)
							(mid 0.249642 0.249642)
							(end 0.1778 0.2794)
						)
					)
					(width 0)
					(fill yes)
				)
			)
		)
	)
	(footprint ""
		(layer "B.Cu")
		(at 197.485 -47.8028 -90)
		(property "Reference" "L17"
			(at 0 0 90)
			(layer "B.SilkS")
			(hide yes)
			(effects
				(font
					(size 1.27 1.27)
				)
				(justify mirror)
			)
		)
		(property "Value" "MPZ2012S601AT-GP"
			(at 0 -4.2418 270)
			(unlocked yes)
			(layer "B.Fab")
			(hide yes)
			(effects
				(font
					(size 1.016 1.016)
					(thickness 0.1524)
				)
				(justify mirror)
			)
		)
		(property "Device Type" "L805H42"
			(at 0 -5.7912 270)
			(unlocked yes)
			(layer "B.Fab")
			(hide yes)
			(effects
				(font
					(size 1.016 1.016)
					(thickness 0.1524)
				)
				(justify mirror)
			)
		)
		(duplicate_pad_numbers_are_jumpers no)
		(fp_line
			(start -0.889 1.7018)
			(end 0.889 1.7018)
			(stroke
				(width 0.1524)
				(type default)
			)
			(layer "B.SilkS")
		)
		(fp_line
			(start 0.889 1.7018)
			(end 0.889 -1.7018)
			(stroke
				(width 0.1524)
				(type default)
			)
			(layer "B.SilkS")
		)
		(fp_line
			(start -0.889 -1.7018)
			(end -0.889 1.7018)
			(stroke
				(width 0.1524)
				(type default)
			)
			(layer "B.SilkS")
		)
		(fp_line
			(start 0.889 -1.7018)
			(end -0.889 -1.7018)
			(stroke
				(width 0.1524)
				(type default)
			)
			(layer "B.SilkS")
		)
		(fp_rect
			(start 0.9652 1.778)
			(end -0.9652 -1.778)
			(stroke
				(width 0)
				(type default)
			)
			(fill no)
			(layer "B.CrtYd")
		)
		(fp_rect
			(start 0.9652 1.778)
			(end -0.9652 -1.778)
			(stroke
				(width 0)
				(type default)
			)
			(fill no)
			(layer "B.Fab")
		)
		(pad "1" smd rect
			(at 0 -0.9652 90)
			(size 1.397 1.143)
			(layers "B.Cu" "B.Mask" "B.Paste")
			(net "VDDA_SAS_REF_CLK")
		)
		(pad "2" smd rect
			(at 0 0.9652 90)
			(size 1.397 1.143)
			(layers "B.Cu" "B.Mask" "B.Paste")
			(net "P1V8")
		)
	)
	(footprint ""
		(layer "B.Cu")
		(at 92.5068 -168.7068 -90)
		(property "Reference" "R419"
			(at 0 0 90)
			(layer "B.SilkS")
			(hide yes)
			(effects
				(font
					(size 1.27 1.27)
				)
				(justify mirror)
			)
		)
		(property "Value" "0R2J-2-GP"
			(at -0.064008 -3.993896 270)
			(unlocked yes)
			(layer "B.Fab")
			(hide yes)
			(effects
				(font
					(size 1.016 1.016)
					(thickness 0.1524)
				)
				(justify mirror)
			)
		)
		(property "Device Type" "R402H16"
			(at -0.064008 -5.517896 270)
			(unlocked yes)
			(layer "B.Fab")
			(hide yes)
			(effects
				(font
					(size 1.016 1.016)
					(thickness 0.1524)
				)
				(justify mirror)
			)
		)
		(duplicate_pad_numbers_are_jumpers no)
		(fp_line
			(start -0.508 -0.9398)
			(end 0.508 -0.9398)
			(stroke
				(width 0.1524)
				(type default)
			)
			(layer "B.SilkS")
		)
		(fp_line
			(start 0.508 -0.9398)
			(end 0.508 0.9398)
			(stroke
				(width 0.1524)
				(type default)
			)
			(layer "B.SilkS")
		)
		(fp_rect
			(start 0.508 0.9398)
			(end -0.508 -0.9398)
			(stroke
				(width 0)
				(type default)
			)
			(fill no)
			(layer "B.CrtYd")
		)
		(fp_rect
			(start 0.508 0.9398)
			(end -0.508 -0.9398)
			(stroke
				(width 0)
				(type default)
			)
			(fill no)
			(layer "B.Fab")
		)
		(pad "1" smd custom
			(at 0 -0.4445 90)
			(size 0.1397 0.1397)
			(layers "B.Cu" "B.Mask" "B.Paste")
			(net "UART_COMP_RX")
			(options
				(clearance outline)
				(anchor circle)
			)
			(primitives
				(gr_poly
					(pts
						(arc
							(start -0.1778 0.2794)
							(mid -0.249642 0.249642)
							(end -0.2794 0.1778)
						)
						(arc
							(start -0.2794 -0.1778)
							(mid -0.249642 -0.249642)
							(end -0.1778 -0.2794)
						)
						(arc
							(start 0.1778 -0.2794)
							(mid 0.249642 -0.249642)
							(end 0.2794 -0.1778)
						)
						(arc
							(start 0.2794 0.1778)
							(mid 0.249642 0.249642)
							(end 0.1778 0.2794)
						)
					)
					(width 0)
					(fill yes)
				)
			)
		)
		(pad "2" smd custom
			(at 0 0.4445 90)
			(size 0.1397 0.1397)
			(layers "B.Cu" "B.Mask" "B.Paste")
			(net "UART_COMP_R_RX")
			(options
				(clearance outline)
				(anchor circle)
			)
			(primitives
				(gr_poly
					(pts
						(arc
							(start -0.1778 0.2794)
							(mid -0.249642 0.249642)
							(end -0.2794 0.1778)
						)
						(arc
							(start -0.2794 -0.1778)
							(mid -0.249642 -0.249642)
							(end -0.1778 -0.2794)
						)
						(arc
							(start 0.1778 -0.2794)
							(mid 0.249642 -0.249642)
							(end 0.2794 -0.1778)
						)
						(arc
							(start 0.2794 0.1778)
							(mid 0.249642 0.249642)
							(end 0.1778 0.2794)
						)
					)
					(width 0)
					(fill yes)
				)
			)
		)
	)
	(footprint ""
		(layer "B.Cu")
		(at 88.265 -179.832)
		(property "Reference" "R97"
			(at 0 0 0)
			(layer "B.SilkS")
			(hide yes)
			(effects
				(font
					(size 1.27 1.27)
				)
				(justify mirror)
			)
		)
		(property "Value" "0R2J-2-GP"
			(at -0.064008 -3.993896 0)
			(unlocked yes)
			(layer "B.Fab")
			(hide yes)
			(effects
				(font
					(size 1.016 1.016)
					(thickness 0.1524)
				)
				(justify mirror)
			)
		)
		(property "Device Type" "R402H16"
			(at -0.064008 -5.517896 0)
			(unlocked yes)
			(layer "B.Fab")
			(hide yes)
			(effects
				(font
					(size 1.016 1.016)
					(thickness 0.1524)
				)
				(justify mirror)
			)
		)
		(duplicate_pad_numbers_are_jumpers no)
		(fp_line
			(start -0.508 -0.9398)
			(end 0.508 -0.9398)
			(stroke
				(width 0.1524)
				(type default)
			)
			(layer "B.SilkS")
		)
		(fp_line
			(start 0.508 -0.9398)
			(end 0.508 0.9398)
			(stroke
				(width 0.1524)
				(type default)
			)
			(layer "B.SilkS")
		)
		(fp_rect
			(start 0.508 0.9398)
			(end -0.508 -0.9398)
			(stroke
				(width 0)
				(type default)
			)
			(fill no)
			(layer "B.CrtYd")
		)
		(fp_rect
			(start 0.508 0.9398)
			(end -0.508 -0.9398)
			(stroke
				(width 0)
				(type default)
			)
			(fill no)
			(layer "B.Fab")
		)
		(pad "1" smd custom
			(at 0 -0.4445 180)
			(size 0.1397 0.1397)
			(layers "B.Cu" "B.Mask" "B.Paste")
			(net "I2C_BMC_COMP_SDA_OUT")
			(options
				(clearance outline)
				(anchor circle)
			)
			(primitives
				(gr_poly
					(pts
						(arc
							(start -0.1778 0.2794)
							(mid -0.249642 0.249642)
							(end -0.2794 0.1778)
						)
						(arc
							(start -0.2794 -0.1778)
							(mid -0.249642 -0.249642)
							(end -0.1778 -0.2794)
						)
						(arc
							(start 0.1778 -0.2794)
							(mid 0.249642 -0.249642)
							(end 0.2794 -0.1778)
						)
						(arc
							(start 0.2794 0.1778)
							(mid 0.249642 0.249642)
							(end 0.1778 0.2794)
						)
					)
					(width 0)
					(fill yes)
				)
			)
		)
		(pad "2" smd custom
			(at 0 0.4445 180)
			(size 0.1397 0.1397)
			(layers "B.Cu" "B.Mask" "B.Paste")
			(net "I2C_BMC_COMP_SDA_R")
			(options
				(clearance outline)
				(anchor circle)
			)
			(primitives
				(gr_poly
					(pts
						(arc
							(start -0.1778 0.2794)
							(mid -0.249642 0.249642)
							(end -0.2794 0.1778)
						)
						(arc
							(start -0.2794 -0.1778)
							(mid -0.249642 -0.249642)
							(end -0.1778 -0.2794)
						)
						(arc
							(start 0.1778 -0.2794)
							(mid 0.249642 -0.249642)
							(end 0.2794 -0.1778)
						)
						(arc
							(start 0.2794 0.1778)
							(mid 0.249642 0.249642)
							(end 0.1778 0.2794)
						)
					)
					(width 0)
					(fill yes)
				)
			)
		)
	)
)
